# T6G (Grand Teton) — schematic netlist excerpt (pin names and nets, part order shuffled) for the footprints in the layout excerpt that follows; sources: Cadence DE-HDL packaged netlist, KiCad conversion of 04192023_DAF0TMB3IC0_F0TG_MB_C_brd_V02_OCP.brd

J23  SCONN288_DDR506112002KQ  IO  pkg DDR288S_1-1VXC  page 91
  VIN_BULK0  = P12V_MEM_CPU0
  RFU0  = NC
  VIN_MGMT  = P3V3_AUX
  HSCL  = I3C_SPD_DDRF_CPU0_SCL
  HSDA  = I3C_SPD_DDRF_CPU0_SDA
  VSS0  = GND
  DQ0_A  = M_F_CPU0_SA_DQ<0>
  VSS1  = GND
  DQ1_A  = M_F_CPU0_SA_DQ<1>
  VSS2  = GND
  DQS0_A_T  = M_F_CPU0_SA_DQS_DP<0>
  DQS0_A_C  = M_F_CPU0_SA_DQS_DN<0>
  VSS3  = GND
  DQ4_A  = M_F_CPU0_SA_DQ<4>
  VSS4  = GND
  DQ5_A  = M_F_CPU0_SA_DQ<5>
  VSS5  = GND
  DQ8_A  = M_F_CPU0_SA_DQ<8>
  VSS6  = GND
  DQ9_A  = M_F_CPU0_SA_DQ<9>
  VSS7  = GND
  DQS1_A_T  = M_F_CPU0_SA_DQS_DP<1>
  DQS1_A_C  = M_F_CPU0_SA_DQS_DN<1>
  VSS8  = GND
  DQ12_A  = M_F_CPU0_SA_DQ<12>
  VSS9  = GND
  DQ13_A  = M_F_CPU0_SA_DQ<13>
  VSS10  = GND
  DQ16_A  = M_F_CPU0_SA_DQ<16>
  VSS11  = GND
  DQ17_A  = M_F_CPU0_SA_DQ<17>
  VSS12  = GND
  DQS2_A_T  = M_F_CPU0_SA_DQS_DP<2>
  DQS2_A_C  = M_F_CPU0_SA_DQS_DN<2>
  VSS13  = GND
  DQ20_A  = M_F_CPU0_SA_DQ<20>
  VSS14  = GND
  DQ21_A  = M_F_CPU0_SA_DQ<21>
  VSS15  = GND
  DQ24_A  = M_F_CPU0_SA_DQ<24>
  VSS16  = GND
  DQ25_A  = M_F_CPU0_SA_DQ<25>
  VSS17  = GND
  DQS3_A_T  = M_F_CPU0_SA_DQS_DP<3>
  DQS3_A_C  = M_F_CPU0_SA_DQS_DN<3>
  VSS18  = GND
  DQ28_A  = M_F_CPU0_SA_DQ<28>
  VSS19  = GND
  DQ29_A  = M_F_CPU0_SA_DQ<29>
  VSS20  = GND
  CB0_A  = M_F_CPU0_SA_CB<0>
  VSS21  = GND
  CB1_A  = M_F_CPU0_SA_CB<1>
  VSS22  = GND
  DQS4_A_T  = M_F_CPU0_SA_DQS_DP<4>
  DQS4_A_C  = M_F_CPU0_SA_DQS_DN<4>
  VSS23  = GND
  CB4_A  = M_F_CPU0_SA_CB<4>
  VSS24  = GND
  CB5_A  = M_F_CPU0_SA_CB<5>
  VSS25  = GND
  ALERT_N  = M_F_CPU0_ALERT_N
  VSS26  = GND
  CS0_A_N  = M_F_CPU0_SA_CS_N<0>
  VSS27  = GND
  CA0_A  = M_F_CPU0_SA_CA<0>
  VSS28  = GND
  CA2_A  = M_F_CPU0_SA_CA<2>
  VSS29  = GND
  CA4_A  = M_F_CPU0_SA_CA<4>
  VSS30  = GND
  CA6_A  = M_F_CPU0_SA_CA<6>
  VSS31  = GND
  PAR_A  = M_F_CPU0_SA_PAR
  VSS32  = GND
  CA0_B  = M_F_CPU0_SB_CA<0>
  VSS33  = GND
  CA2_B  = M_F_CPU0_SB_CA<2>
  VSS34  = GND
  CA4_B  = M_F_CPU0_SB_CA<4>
  VSS35  = GND
  CA6_B  = M_F_CPU0_SB_CA<6>
  VSS36  = GND
  CS0_B_N  = M_F_CPU0_SB_CS_N<0>
  VSS37  = GND
  \lbd||rsp_a_n\  = M_F_CPU0_SA_RSP<0>
  \lbs||rsp_b_n\  = M_F_CPU0_SB_RSP<0>
  VSS38  = GND
  CB4_B  = M_F_CPU0_SB_CB<4>
  VSS39  = GND
  CB5_B  = M_F_CPU0_SB_CB<5>
  VSS40  = GND
  \dqs9_b_t||tdqs9_b_t||dbi4_b_n\  = M_F_CPU0_SB_DQS_DP<9>
  \dqs9_b_c||tdqs9_b_c\  = M_F_CPU0_SB_DQS_DN<9>
  VSS41  = GND
  CB0_B  = M_F_CPU0_SB_CB<0>
  VSS42  = GND
  CB1_B  = M_F_CPU0_SB_CB<1>
  VSS43  = GND
  DQ0_B  = M_F_CPU0_SB_DQ<0>
  VSS44  = GND
  DQ1_B  = M_F_CPU0_SB_DQ<1>
  VSS45  = GND
  DQS0_B_T  = M_F_CPU0_SB_DQS_DP<0>
  DQS0_B_C  = M_F_CPU0_SB_DQS_DN<0>
  VSS46  = GND
  DQ4_B  = M_F_CPU0_SB_DQ<4>
  VSS47  = GND
  DQ5_B  = M_F_CPU0_SB_DQ<5>
  VSS48  = GND
  DQ8_B  = M_F_CPU0_SB_DQ<8>
  VSS49  = GND
  DQ9_B  = M_F_CPU0_SB_DQ<9>
  VSS50  = GND
  DQS1_B_T  = M_F_CPU0_SB_DQS_DP<1>
  DQS1_B_C  = M_F_CPU0_SB_DQS_DN<1>
  VSS51  = GND
  DQ12_B  = M_F_CPU0_SB_DQ<12>
  VSS52  = GND
  DQ13_B  = M_F_CPU0_SB_DQ<13>
  VSS53  = GND
  DQ16_B  = M_F_CPU0_SB_DQ<16>
  VSS54  = GND
  DQ17_B  = M_F_CPU0_SB_DQ<17>
  VSS55  = GND
  DQS2_B_T  = M_F_CPU0_SB_DQS_DP<2>
  DQS2_B_C  = M_F_CPU0_SB_DQS_DN<2>
  VSS56  = GND
  DQ20_B  = M_F_CPU0_SB_DQ<20>
  VSS57  = GND
  DQ21_B  = M_F_CPU0_SB_DQ<21>
  VSS58  = GND
  DQ24_B  = M_F_CPU0_SB_DQ<24>
  VSS59  = GND
  DQ25_B  = M_F_CPU0_SB_DQ<25>
  VSS60  = GND
  DQS3_B_T  = M_F_CPU0_SB_DQS_DP<3>
  DQS3_B_C  = M_F_CPU0_SB_DQS_DN<3>
  VSS61  = GND
  DQ28_B  = M_F_CPU0_SB_DQ<28>
  VSS62  = GND
  DQ29_B  = M_F_CPU0_SB_DQ<29>
  VSS63  = GND
  RFU1  = NC
  VIN_BULK1  = P12V_MEM_CPU0
  VIN_BULK2  = P12V_MEM_CPU0
  \pwr_good||fail_n\  = PWRGD_CHF_CPU0_DIMM
  HAS  = PD_CHF_CPU0_DIMM_SAA
  RFU2  = NC
  RFU3  = NC
  VSS64  = GND
  DQ2_A  = M_F_CPU0_SA_DQ<2>
  VSS65  = GND
  DQ3_A  = M_F_CPU0_SA_DQ<3>
  VSS66  = GND
  \dqs5_a_c||tdqs5_a_c||dqs5_a_t||tdqs5_a_t\  = M_F_CPU0_SA_DQS_DN<5>
  \dqs5_a_t||tdqs5_a_t\  = M_F_CPU0_SA_DQS_DP<5>
  VSS67  = GND
  DQ6_A  = M_F_CPU0_SA_DQ<6>
  VSS68  = GND
  DQ7_A  = M_F_CPU0_SA_DQ<7>
  VSS69  = GND
  DQ10_A  = M_F_CPU0_SA_DQ<10>
  VSS70  = GND
  DQ11_A  = M_F_CPU0_SA_DQ<11>
  VSS71  = GND
  \dqs6_a_c||tdqs6_a_c||dqs6_a_t||tdqs6_a_t\  = M_F_CPU0_SA_DQS_DN<6>
  \dqs6_a_t||tdqs6_a_t\  = M_F_CPU0_SA_DQS_DP<6>
  VSS72  = GND
  DQ14_A  = M_F_CPU0_SA_DQ<14>
  VSS73  = GND
  DQ15_A  = M_F_CPU0_SA_DQ<15>
  VSS74  = GND
  DQ18_A  = M_F_CPU0_SA_DQ<18>
  VSS75  = GND
  DQ19_A  = M_F_CPU0_SA_DQ<19>
  VSS76  = GND
  \dqs7_a_c||tdqs7_a_c\  = M_F_CPU0_SA_DQS_DN<7>
  \dqs7_a_t||tdqs7_a_t\  = M_F_CPU0_SA_DQS_DP<7>
  VSS77  = GND
  DQ22_A  = M_F_CPU0_SA_DQ<22>
  VSS78  = GND
  DQ23_A  = M_F_CPU0_SA_DQ<23>
  VSS79  = GND
  DQ26_A  = M_F_CPU0_SA_DQ<26>
  VSS80  = GND
  DQ27_A  = M_F_CPU0_SA_DQ<27>
  VSS81  = GND
  \dqs8_a_c||tdqs8_a_c\  = M_F_CPU0_SA_DQS_DN<8>
  \dqs8_a_t||tdqs8_a_t\  = M_F_CPU0_SA_DQS_DP<8>
  VSS82  = GND
  DQ30_A  = M_F_CPU0_SA_DQ<30>
  VSS83  = GND
  DQ31_A  = M_F_CPU0_SA_DQ<31>
  VSS84  = GND
  CB2_A  = M_F_CPU0_SA_CB<2>
  VSS85  = GND
  CB3_A  = M_F_CPU0_SA_CB<3>
  VSS86  = GND
  \dqs9_a_c||tdqs9_a_c\  = M_F_CPU0_SA_DQS_DN<9>
  \dqs9_a_t||tdqs9_a_t\  = M_F_CPU0_SA_DQS_DP<9>
  VSS87  = GND
  CB6_A  = M_F_CPU0_SA_CB<6>
  VSS88  = GND
  CB7_A  = M_F_CPU0_SA_CB<7>
  VSS89  = GND
  RESET_N  = M_F_CPU0_RESET_N
  VSS90  = GND
  CS1_A_N  = M_F_CPU0_SA_CS_N<1>
  VSS91  = GND
  CA1_A  = M_F_CPU0_SA_CA<1>
  VSS92  = GND
  CA3_A  = M_F_CPU0_SA_CA<3>
  VSS93  = GND
  CA5_A  = M_F_CPU0_SA_CA<5>
  VSS94  = GND
  CK_T  = M_F_CPU0_CLK_DP<0>
  CK_C  = M_F_CPU0_CLK_DN<0>
  VSS95  = GND
  RFU4  = NC
  CA1_B  = M_F_CPU0_SB_CA<1>
  VSS96  = GND
  CA3_B  = M_F_CPU0_SB_CA<3>
  VSS97  = GND
  CA5_B  = M_F_CPU0_SB_CA<5>
  VSS98  = GND
  PAR_B  = M_F_CPU0_SB_PAR
  VSS99  = GND
  CS1_B_N  = M_F_CPU0_SB_CS_N<1>
  VSS100  = GND
  RFU5  = NC
  RFU6  = NC
  VSS101  = GND
  CB6_B  = M_F_CPU0_SB_CB<6>
  VSS102  = GND
  CB7_B  = M_F_CPU0_SB_CB<7>
  VSS103  = GND
  DQS4_B_C  = M_F_CPU0_SB_DQS_DN<4>
  DQS4_B_T  = M_F_CPU0_SB_DQS_DP<4>
  VSS104  = GND
  CB2_B  = M_F_CPU0_SB_CB<2>
  VSS105  = GND
  CB3_B  = M_F_CPU0_SB_CB<3>
  VSS106  = GND
  DQ2_B  = M_F_CPU0_SB_DQ<2>
  VSS107  = GND
  DQ3_B  = M_F_CPU0_SB_DQ<3>
  VSS108  = GND
  \dqs5_b_c||tdqs5_b_c\  = M_F_CPU0_SB_DQS_DN<5>
  \dqs5_b_t||tdqs5_b_t\  = M_F_CPU0_SB_DQS_DP<5>
  VSS109  = GND
  DQ6_B  = M_F_CPU0_SB_DQ<6>
  VSS110  = GND
  DQ7_B  = M_F_CPU0_SB_DQ<7>
  VSS111  = GND
  DQ10_B  = M_F_CPU0_SB_DQ<10>
  VSS112  = GND
  DQ11_B  = M_F_CPU0_SB_DQ<11>
  VSS113  = GND
  \dqs6_b_c||tdqs6_b_c\  = M_F_CPU0_SB_DQS_DN<6>
  \dqs6_b_t||tdqs6_b_t\  = M_F_CPU0_SB_DQS_DP<6>
  VSS114  = GND
  DQ14_B  = M_F_CPU0_SB_DQ<14>
  VSS115  = GND
  DQ15_B  = M_F_CPU0_SB_DQ<15>
  VSS116  = GND
  DQ18_B  = M_F_CPU0_SB_DQ<18>
  VSS117  = GND
  DQ19_B  = M_F_CPU0_SB_DQ<19>
  VSS118  = GND
  \dqs7_b_c||tdqs7_b_c\  = M_F_CPU0_SB_DQS_DN<7>
  \dqs7_b_t||tdqs7_b_t\  = M_F_CPU0_SB_DQS_DP<7>
  VSS119  = GND
  DQ22_B  = M_F_CPU0_SB_DQ<22>
  VSS120  = GND
  DQ23_B  = M_F_CPU0_SB_DQ<23>
  VSS121  = GND
  DQ26_B  = M_F_CPU0_SB_DQ<26>
  VSS122  = GND
  DQ27_B  = M_F_CPU0_SB_DQ<27>
  VSS123  = GND
  \dqs8_b_c||tdqs8_b_c\  = M_F_CPU0_SB_DQS_DN<8>
  \dqs8_b_t||tdqs8_b_t\  = M_F_CPU0_SB_DQS_DP<8>
  VSS124  = GND
  DQ30_B  = M_F_CPU0_SB_DQ<30>
  VSS125  = GND
  DQ31_B  = M_F_CPU0_SB_DQ<31>
  VSS126  = GND
  G1  = GND
  G2  = GND
  G3  = GND

(kicad_pcb
	(version 20260206)
	(generator "pcbnew")
	(generator_version "10.0")
	(general
		(thickness 1.6)
		(legacy_teardrops no)
	)
	(paper "A4")
	(title_block
		(title "04192023_DAF0TMB3IC0_F0TG_MB_C_brd_V02_OCP.brd")
		(comment 1 "Grand Teton / footprint 2449 of 8354 (J23), pads 185-230 of 291")
	)
	(layers
		(0 "F.Cu" signal "TOP")
		(4 "In1.Cu" signal "GND")
		(6 "In2.Cu" signal "IN1")
		(8 "In3.Cu" signal "GND1")
		(10 "In4.Cu" signal "IN2")
		(12 "In5.Cu" signal "GND2")
		(14 "In6.Cu" signal "IN3")
		(16 "In7.Cu" signal "GND3")
		(18 "In8.Cu" signal "VCC")
		(20 "In9.Cu" signal "VCC1")
		(22 "In10.Cu" signal "GND4")
		(24 "In11.Cu" signal "IN4")
		(26 "In12.Cu" signal "GND5")
		(28 "In13.Cu" signal "IN5")
		(30 "In14.Cu" signal "GND6")
		(32 "In15.Cu" signal "IN6")
		(34 "In16.Cu" signal "GND7")
		(2 "B.Cu" signal "BOTTOM")
		(9 "F.Adhes" user "F.Adhesive")
		(11 "B.Adhes" user "B.Adhesive")
		(13 "F.Paste" user "Package Geometry/Pastemask Top")
		(15 "B.Paste" user "Package Geometry/Pastemask Bottom")
		(5 "F.SilkS" user "Ref Des/Silkscreen Top")
		(7 "B.SilkS" user "Ref Des/Silkscreen Bottom")
		(1 "F.Mask" user "Board Geometry/Soldermask Top")
		(3 "B.Mask" user "Board Geometry/Soldermask Bottom")
		(17 "Dwgs.User" user "User.Drawings")
		(19 "Cmts.User" user "User.Comments")
		(21 "Eco1.User" user "User.Eco1")
		(23 "Eco2.User" user "User.Eco2")
		(25 "Edge.Cuts" user "Board Geometry/Outline")
		(27 "Margin" user)
		(31 "F.CrtYd" user "Package Geometry/Place Bound Top")
		(29 "B.CrtYd" user "Package Geometry/Place Bound Bottom")
		(35 "F.Fab" user "Ref Des/Assembly Top")
		(33 "B.Fab" user "Ref Des/Assembly Bottom")
	)
	(footprint ""
		(layer "F.Cu")
		(at 267.598144 -255.560068 180)
		(property "Reference" "J23"
			(at -2.2098 -81.984088 0)
			(unlocked yes)
			(layer "F.SilkS")
			(effects
				(font
					(size 0.7874 0.5842)
					(thickness 0.1524)
				)
			)
		)
		(property "Value" ""
			(at 0 0 180)
			(layer "F.Fab")
			(effects
				(font
					(size 1.27 1.27)
				)
			)
		)
		(duplicate_pad_numbers_are_jumpers no)
		(pad "185" smd rect
			(at 2.050034 -29.325062 90)
			(size 0.519938 1.4986)
			(layers "F.Cu" "F.Mask" "F.Paste")
			(net "M_F_CPU0_SA_DQ<26>")
		)
		(pad "186" smd rect
			(at 2.050034 -28.474924 90)
			(size 0.519938 1.4986)
			(layers "F.Cu" "F.Mask" "F.Paste")
			(net "GND")
		)
		(pad "187" smd rect
			(at 2.050034 -27.62504 90)
			(size 0.519938 1.4986)
			(layers "F.Cu" "F.Mask" "F.Paste")
			(net "M_F_CPU0_SA_DQ<27>")
		)
		(pad "188" smd rect
			(at 2.050034 -26.774902 90)
			(size 0.519938 1.4986)
			(layers "F.Cu" "F.Mask" "F.Paste")
			(net "GND")
		)
		(pad "189" smd rect
			(at 2.050034 -25.925018 90)
			(size 0.519938 1.4986)
			(layers "F.Cu" "F.Mask" "F.Paste")
			(net "M_F_CPU0_SA_DQS_DN<8>")
		)
		(pad "190" smd rect
			(at 2.050034 -25.07488 90)
			(size 0.519938 1.4986)
			(layers "F.Cu" "F.Mask" "F.Paste")
			(net "M_F_CPU0_SA_DQS_DP<8>")
		)
		(pad "191" smd rect
			(at 2.050034 -24.224996 90)
			(size 0.519938 1.4986)
			(layers "F.Cu" "F.Mask" "F.Paste")
			(net "GND")
		)
		(pad "192" smd rect
			(at 2.050034 -23.375112 90)
			(size 0.519938 1.4986)
			(layers "F.Cu" "F.Mask" "F.Paste")
			(net "M_F_CPU0_SA_DQ<30>")
		)
		(pad "193" smd rect
			(at 2.050034 -22.524974 90)
			(size 0.519938 1.4986)
			(layers "F.Cu" "F.Mask" "F.Paste")
			(net "GND")
		)
		(pad "194" smd rect
			(at 2.050034 -21.67509 90)
			(size 0.519938 1.4986)
			(layers "F.Cu" "F.Mask" "F.Paste")
			(net "M_F_CPU0_SA_DQ<31>")
		)
		(pad "195" smd rect
			(at 2.050034 -20.824952 90)
			(size 0.519938 1.4986)
			(layers "F.Cu" "F.Mask" "F.Paste")
			(net "GND")
		)
		(pad "196" smd rect
			(at 2.050034 -19.975068 90)
			(size 0.519938 1.4986)
			(layers "F.Cu" "F.Mask" "F.Paste")
			(net "M_F_CPU0_SA_CB<2>")
		)
		(pad "197" smd rect
			(at 2.050034 -19.12493 90)
			(size 0.519938 1.4986)
			(layers "F.Cu" "F.Mask" "F.Paste")
			(net "GND")
		)
		(pad "198" smd rect
			(at 2.050034 -18.275046 90)
			(size 0.519938 1.4986)
			(layers "F.Cu" "F.Mask" "F.Paste")
			(net "M_F_CPU0_SA_CB<3>")
		)
		(pad "199" smd rect
			(at 2.050034 -17.424908 90)
			(size 0.519938 1.4986)
			(layers "F.Cu" "F.Mask" "F.Paste")
			(net "GND")
		)
		(pad "200" smd rect
			(at 2.050034 -16.575024 90)
			(size 0.519938 1.4986)
			(layers "F.Cu" "F.Mask" "F.Paste")
			(net "M_F_CPU0_SA_DQS_DN<9>")
		)
		(pad "201" smd rect
			(at 2.050034 -15.724886 90)
			(size 0.519938 1.4986)
			(layers "F.Cu" "F.Mask" "F.Paste")
			(net "M_F_CPU0_SA_DQS_DP<9>")
		)
		(pad "202" smd rect
			(at 2.050034 -14.875002 90)
			(size 0.519938 1.4986)
			(layers "F.Cu" "F.Mask" "F.Paste")
			(net "GND")
		)
		(pad "203" smd rect
			(at 2.050034 -14.025118 90)
			(size 0.519938 1.4986)
			(layers "F.Cu" "F.Mask" "F.Paste")
			(net "M_F_CPU0_SA_CB<6>")
		)
		(pad "204" smd rect
			(at 2.050034 -13.17498 90)
			(size 0.519938 1.4986)
			(layers "F.Cu" "F.Mask" "F.Paste")
			(net "GND")
		)
		(pad "205" smd rect
			(at 2.050034 -12.325096 90)
			(size 0.519938 1.4986)
			(layers "F.Cu" "F.Mask" "F.Paste")
			(net "M_F_CPU0_SA_CB<7>")
		)
		(pad "206" smd rect
			(at 2.050034 -11.474958 90)
			(size 0.519938 1.4986)
			(layers "F.Cu" "F.Mask" "F.Paste")
			(net "GND")
		)
		(pad "207" smd rect
			(at 2.050034 -10.625074 90)
			(size 0.519938 1.4986)
			(layers "F.Cu" "F.Mask" "F.Paste")
			(net "M_F_CPU0_RESET_N")
		)
		(pad "208" smd rect
			(at 2.050034 -9.774936 90)
			(size 0.519938 1.4986)
			(layers "F.Cu" "F.Mask" "F.Paste")
			(net "GND")
		)
		(pad "209" smd rect
			(at 2.050034 -8.925052 90)
			(size 0.519938 1.4986)
			(layers "F.Cu" "F.Mask" "F.Paste")
			(net "M_F_CPU0_SA_CS_N<1>")
		)
		(pad "210" smd rect
			(at 2.050034 -8.074914 90)
			(size 0.519938 1.4986)
			(layers "F.Cu" "F.Mask" "F.Paste")
			(net "GND")
		)
		(pad "211" smd rect
			(at 2.050034 -7.22503 90)
			(size 0.519938 1.4986)
			(layers "F.Cu" "F.Mask" "F.Paste")
			(net "M_F_CPU0_SA_CA<1>")
		)
		(pad "212" smd rect
			(at 2.050034 -6.374892 90)
			(size 0.519938 1.4986)
			(layers "F.Cu" "F.Mask" "F.Paste")
			(net "GND")
		)
		(pad "213" smd rect
			(at 2.050034 -5.525008 90)
			(size 0.519938 1.4986)
			(layers "F.Cu" "F.Mask" "F.Paste")
			(net "M_F_CPU0_SA_CA<3>")
		)
		(pad "214" smd rect
			(at 2.050034 -4.675124 90)
			(size 0.519938 1.4986)
			(layers "F.Cu" "F.Mask" "F.Paste")
			(net "GND")
		)
		(pad "215" smd rect
			(at 2.050034 -3.824986 90)
			(size 0.519938 1.4986)
			(layers "F.Cu" "F.Mask" "F.Paste")
			(net "M_F_CPU0_SA_CA<5>")
		)
		(pad "216" smd rect
			(at 2.050034 -2.975102 90)
			(size 0.519938 1.4986)
			(layers "F.Cu" "F.Mask" "F.Paste")
			(net "GND")
		)
		(pad "217" smd rect
			(at 2.050034 -2.124964 90)
			(size 0.519938 1.4986)
			(layers "F.Cu" "F.Mask" "F.Paste")
			(net "M_F_CPU0_CLK_DP<0>")
		)
		(pad "218" smd rect
			(at 2.050034 -1.27508 90)
			(size 0.519938 1.4986)
			(layers "F.Cu" "F.Mask" "F.Paste")
			(net "M_F_CPU0_CLK_DN<0>")
		)
		(pad "219" smd rect
			(at 2.050034 -0.424942 90)
			(size 0.519938 1.4986)
			(layers "F.Cu" "F.Mask" "F.Paste")
			(net "GND")
		)
		(pad "220" smd rect
			(at 2.050034 5.525008 90)
			(size 0.519938 1.4986)
			(layers "F.Cu" "F.Mask" "F.Paste")
			(net "Net_2323")
		)
		(pad "221" smd rect
			(at 2.050034 6.374892 90)
			(size 0.519938 1.4986)
			(layers "F.Cu" "F.Mask" "F.Paste")
			(net "M_F_CPU0_SB_CA<1>")
		)
		(pad "222" smd rect
			(at 2.050034 7.22503 90)
			(size 0.519938 1.4986)
			(layers "F.Cu" "F.Mask" "F.Paste")
			(net "GND")
		)
		(pad "223" smd rect
			(at 2.050034 8.074914 90)
			(size 0.519938 1.4986)
			(layers "F.Cu" "F.Mask" "F.Paste")
			(net "M_F_CPU0_SB_CA<3>")
		)
		(pad "224" smd rect
			(at 2.050034 8.925052 90)
			(size 0.519938 1.4986)
			(layers "F.Cu" "F.Mask" "F.Paste")
			(net "GND")
		)
		(pad "225" smd rect
			(at 2.050034 9.774936 90)
			(size 0.519938 1.4986)
			(layers "F.Cu" "F.Mask" "F.Paste")
			(net "M_F_CPU0_SB_CA<5>")
		)
		(pad "226" smd rect
			(at 2.050034 10.625074 90)
			(size 0.519938 1.4986)
			(layers "F.Cu" "F.Mask" "F.Paste")
			(net "GND")
		)
		(pad "227" smd rect
			(at 2.050034 11.474958 90)
			(size 0.519938 1.4986)
			(layers "F.Cu" "F.Mask" "F.Paste")
			(net "M_F_CPU0_SB_PAR")
		)
		(pad "228" smd rect
			(at 2.050034 12.325096 90)
			(size 0.519938 1.4986)
			(layers "F.Cu" "F.Mask" "F.Paste")
			(net "GND")
		)
		(pad "229" smd rect
			(at 2.050034 13.17498 90)
			(size 0.519938 1.4986)
			(layers "F.Cu" "F.Mask" "F.Paste")
			(net "M_F_CPU0_SB_CS_N<1>")
		)
		(pad "230" smd rect
			(at 2.050034 14.025118 90)
			(size 0.519938 1.4986)
			(layers "F.Cu" "F.Mask" "F.Paste")
			(net "GND")
		)
	)
)
